# T6G (Grand Teton) — schematic netlist excerpt (pin names and nets, part order shuffled) for the footprints in the layout excerpt that follows; sources: Cadence DE-HDL packaged netlist, KiCad conversion of 04192023_DAF0TMB3IC0_F0TG_MB_C_brd_V02_OCP.brd

PR51  Q_RES  49.9 1% CHIP  pkg 0402LF  page 200 : A = VSENSE_PVDDCR_CPU1_P0_DP ; B = PVDDCR_CPU1_P0

U151  SN74AVC4T774PWR  IC  pkg TSSOP16XC  page 173
  DIR1  = PVDD18_S5_P0
  DIR2  = PVDD18_S5_P0
  A1  = JTAG_TCK
  A2  = JTAG_TMS
  A3  = JTAG_TRST_N
  A4  = JTAG_DBREQ_N
  DIR3  = PVDD18_S5_P0
  DIR4  = PVDD18_S5_P0
  OE  = CPU1_JTAG_BUF_OE
  GND  = GND
  B4  = JTAG_P1_R_DBREQ_N
  B3  = JTAG_P1_R_TRST_N
  B2  = JTAG_P1_R_TMS
  B1  = JTAG_P1_R_TCK
  VCCB  = PVDD18_S5_P1
  VCCA  = PVDD18_S5_P0

(kicad_pcb
	(version 20260206)
	(generator "pcbnew")
	(generator_version "10.0")
	(general
		(thickness 1.6)
		(legacy_teardrops no)
	)
	(paper "A4")
	(title_block
		(title "04192023_DAF0TMB3IC0_F0TG_MB_C_brd_V02_OCP.brd")
		(comment 1 "Grand Teton / footprints 778-779 of 8354")
	)
	(layers
		(0 "F.Cu" signal "TOP")
		(4 "In1.Cu" signal "GND")
		(6 "In2.Cu" signal "IN1")
		(8 "In3.Cu" signal "GND1")
		(10 "In4.Cu" signal "IN2")
		(12 "In5.Cu" signal "GND2")
		(14 "In6.Cu" signal "IN3")
		(16 "In7.Cu" signal "GND3")
		(18 "In8.Cu" signal "VCC")
		(20 "In9.Cu" signal "VCC1")
		(22 "In10.Cu" signal "GND4")
		(24 "In11.Cu" signal "IN4")
		(26 "In12.Cu" signal "GND5")
		(28 "In13.Cu" signal "IN5")
		(30 "In14.Cu" signal "GND6")
		(32 "In15.Cu" signal "IN6")
		(34 "In16.Cu" signal "GND7")
		(2 "B.Cu" signal "BOTTOM")
		(9 "F.Adhes" user "F.Adhesive")
		(11 "B.Adhes" user "B.Adhesive")
		(13 "F.Paste" user "Package Geometry/Pastemask Top")
		(15 "B.Paste" user "Package Geometry/Pastemask Bottom")
		(5 "F.SilkS" user "Ref Des/Silkscreen Top")
		(7 "B.SilkS" user "Ref Des/Silkscreen Bottom")
		(1 "F.Mask" user "Board Geometry/Soldermask Top")
		(3 "B.Mask" user "Board Geometry/Soldermask Bottom")
		(17 "Dwgs.User" user "User.Drawings")
		(19 "Cmts.User" user "User.Comments")
		(21 "Eco1.User" user "User.Eco1")
		(23 "Eco2.User" user "User.Eco2")
		(25 "Edge.Cuts" user "Board Geometry/Outline")
		(27 "Margin" user)
		(31 "F.CrtYd" user "Package Geometry/Place Bound Top")
		(29 "B.CrtYd" user "Package Geometry/Place Bound Bottom")
		(35 "F.Fab" user "Ref Des/Assembly Top")
		(33 "B.Fab" user "Ref Des/Assembly Bottom")
	)
	(footprint ""
		(layer "F.Cu")
		(at 281.46629 -97.644204 180)
		(property "Reference" "U151"
			(at 3.44678 -3.32486 0)
			(unlocked yes)
			(layer "F.SilkS")
			(effects
				(font
					(size 0.7874 0.5842)
					(thickness 0.1524)
				)
				(justify left)
			)
		)
		(property "Value" ""
			(at 0 0 180)
			(layer "F.Fab")
			(effects
				(font
					(size 1.27 1.27)
				)
			)
		)
		(duplicate_pad_numbers_are_jumpers no)
		(fp_line
			(start 1.868932 2.549906)
			(end 1.868932 -2.549906)
			(stroke
				(width 0.1524)
				(type default)
			)
			(layer "F.SilkS")
		)
		(fp_line
			(start 1.868932 -2.549906)
			(end 1.025906 -2.549906)
			(stroke
				(width 0.1524)
				(type default)
			)
			(layer "F.SilkS")
		)
		(fp_line
			(start 1.025906 -2.549906)
			(end 0 -1.524)
			(stroke
				(width 0.1524)
				(type default)
			)
			(layer "F.SilkS")
		)
		(fp_line
			(start 0 -1.524)
			(end -1.025906 -2.549906)
			(stroke
				(width 0.1524)
				(type default)
			)
			(layer "F.SilkS")
		)
		(fp_line
			(start -1.025906 -2.549906)
			(end -1.868932 -2.549906)
			(stroke
				(width 0.1524)
				(type default)
			)
			(layer "F.SilkS")
		)
		(fp_line
			(start -1.868932 2.549906)
			(end 1.868932 2.549906)
			(stroke
				(width 0.1524)
				(type default)
			)
			(layer "F.SilkS")
		)
		(fp_line
			(start -1.868932 -2.549906)
			(end -1.868932 2.549906)
			(stroke
				(width 0.1524)
				(type default)
			)
			(layer "F.SilkS")
		)
		(fp_poly
			(pts
				(xy -3.593338 -2.533142) (xy -4.729226 -2.533142) (xy -4.27482 -3.4417)
			)
			(stroke
				(width 0)
				(type default)
			)
			(fill yes)
			(layer "F.SilkS")
		)
		(fp_line
			(start 2.249932 2.549906)
			(end 2.249932 -2.549906)
			(stroke
				(width 0.1)
				(type default)
			)
			(layer "F.Fab")
		)
		(fp_line
			(start 2.249932 -2.549906)
			(end -2.249932 -2.549906)
			(stroke
				(width 0.1)
				(type default)
			)
			(layer "F.Fab")
		)
		(fp_line
			(start -2.249932 2.549906)
			(end 2.249932 2.549906)
			(stroke
				(width 0.1)
				(type default)
			)
			(layer "F.Fab")
		)
		(fp_line
			(start -2.249932 -2.549906)
			(end -2.249932 2.549906)
			(stroke
				(width 0.1)
				(type default)
			)
			(layer "F.Fab")
		)
		(fp_poly
			(pts
				(xy -4.7752 -1.787398) (xy -4.7752 -2.803398) (xy -3.7592 -2.295398)
			)
			(stroke
				(width 0)
				(type default)
			)
			(fill yes)
			(layer "F.Fab")
		)
		(pad "1" smd rect
			(at -2.800096 -2.275078 90)
			(size 0.3556 1.6002)
			(layers "F.Cu" "F.Mask" "F.Paste")
			(net "PVDD18_S5_P0")
		)
		(pad "2" smd rect
			(at -2.800096 -1.625092 90)
			(size 0.3556 1.6002)
			(layers "F.Cu" "F.Mask" "F.Paste")
			(net "PVDD18_S5_P0")
		)
		(pad "3" smd rect
			(at -2.800096 -0.975106 90)
			(size 0.3556 1.6002)
			(layers "F.Cu" "F.Mask" "F.Paste")
			(net "JTAG_TCK")
		)
		(pad "4" smd rect
			(at -2.800096 -0.32512 90)
			(size 0.3556 1.6002)
			(layers "F.Cu" "F.Mask" "F.Paste")
			(net "JTAG_TMS")
		)
		(pad "5" smd rect
			(at -2.800096 0.32512 90)
			(size 0.3556 1.6002)
			(layers "F.Cu" "F.Mask" "F.Paste")
			(net "JTAG_TRST_N")
		)
		(pad "6" smd rect
			(at -2.800096 0.975106 90)
			(size 0.3556 1.6002)
			(layers "F.Cu" "F.Mask" "F.Paste")
			(net "JTAG_DBREQ_N")
		)
		(pad "7" smd rect
			(at -2.800096 1.625092 90)
			(size 0.3556 1.6002)
			(layers "F.Cu" "F.Mask" "F.Paste")
			(net "PVDD18_S5_P0")
		)
		(pad "8" smd rect
			(at -2.800096 2.275078 90)
			(size 0.3556 1.6002)
			(layers "F.Cu" "F.Mask" "F.Paste")
			(net "PVDD18_S5_P0")
		)
		(pad "9" smd rect
			(at 2.800096 2.275078 90)
			(size 0.3556 1.6002)
			(layers "F.Cu" "F.Mask" "F.Paste")
			(net "CPU1_JTAG_BUF_OE")
		)
		(pad "10" smd rect
			(at 2.800096 1.625092 90)
			(size 0.3556 1.6002)
			(layers "F.Cu" "F.Mask" "F.Paste")
			(net "GND")
		)
		(pad "11" smd rect
			(at 2.800096 0.975106 90)
			(size 0.3556 1.6002)
			(layers "F.Cu" "F.Mask" "F.Paste")
			(net "JTAG_P1_R_DBREQ_N")
		)
		(pad "12" smd rect
			(at 2.800096 0.32512 90)
			(size 0.3556 1.6002)
			(layers "F.Cu" "F.Mask" "F.Paste")
			(net "JTAG_P1_R_TRST_N")
		)
		(pad "13" smd rect
			(at 2.800096 -0.32512 90)
			(size 0.3556 1.6002)
			(layers "F.Cu" "F.Mask" "F.Paste")
			(net "JTAG_P1_R_TMS")
		)
		(pad "14" smd rect
			(at 2.800096 -0.975106 90)
			(size 0.3556 1.6002)
			(layers "F.Cu" "F.Mask" "F.Paste")
			(net "JTAG_P1_R_TCK")
		)
		(pad "15" smd rect
			(at 2.800096 -1.625092 90)
			(size 0.3556 1.6002)
			(layers "F.Cu" "F.Mask" "F.Paste")
			(net "PVDD18_S5_P1")
		)
		(pad "16" smd rect
			(at 2.800096 -2.275078 90)
			(size 0.3556 1.6002)
			(layers "F.Cu" "F.Mask" "F.Paste")
			(net "PVDD18_S5_P0")
		)
	)
	(footprint ""
		(layer "F.Cu")
		(at 357.93426 -327.60031 180)
		(property "Reference" "PR51"
			(at 0 0 180)
			(layer "F.SilkS")
			(hide yes)
			(effects
				(font
					(size 1.27 1.27)
				)
			)
		)
		(property "Value" ""
			(at 0 0 180)
			(layer "F.Fab")
			(effects
				(font
					(size 1.27 1.27)
				)
			)
		)
		(duplicate_pad_numbers_are_jumpers no)
		(fp_line
			(start 0.7874 0.4064)
			(end -0.7874 0.4064)
			(stroke
				(width 0.1524)
				(type default)
			)
			(layer "F.SilkS")
		)
		(fp_line
			(start 0.7874 -0.4064)
			(end 0.7874 0.4064)
			(stroke
				(width 0.1524)
				(type default)
			)
			(layer "F.SilkS")
		)
		(fp_line
			(start -0.7874 0.4064)
			(end -0.7874 -0.4064)
			(stroke
				(width 0.1524)
				(type default)
			)
			(layer "F.SilkS")
		)
		(fp_line
			(start -0.7874 -0.4064)
			(end 0.7874 -0.4064)
			(stroke
				(width 0.1524)
				(type default)
			)
			(layer "F.SilkS")
		)
		(fp_line
			(start 0.67945 0.3048)
			(end 0.120396 0.3048)
			(stroke
				(width 0.1)
				(type default)
			)
			(layer "F.Fab")
		)
		(fp_line
			(start 0.67945 -0.3048)
			(end 0.67945 0.3048)
			(stroke
				(width 0.1)
				(type default)
			)
			(layer "F.Fab")
		)
		(fp_line
			(start 0.12065 -0.2794)
			(end 0.12065 -0.3048)
			(stroke
				(width 0.1)
				(type default)
			)
			(layer "F.Fab")
		)
		(fp_line
			(start 0.12065 -0.3048)
			(end 0.67945 -0.3048)
			(stroke
				(width 0.1)
				(type default)
			)
			(layer "F.Fab")
		)
		(fp_line
			(start 0.120396 0.3048)
			(end 0.120396 0.2794)
			(stroke
				(width 0.1)
				(type default)
			)
			(layer "F.Fab")
		)
		(fp_line
			(start 0.120396 0.2794)
			(end -0.12065 0.2794)
			(stroke
				(width 0.1)
				(type default)
			)
			(layer "F.Fab")
		)
		(fp_line
			(start -0.12065 0.3048)
			(end -0.67945 0.3048)
			(stroke
				(width 0.1)
				(type default)
			)
			(layer "F.Fab")
		)
		(fp_line
			(start -0.12065 0.2794)
			(end -0.12065 0.3048)
			(stroke
				(width 0.1)
				(type default)
			)
			(layer "F.Fab")
		)
		(fp_line
			(start -0.12065 -0.2794)
			(end 0.12065 -0.2794)
			(stroke
				(width 0.1)
				(type default)
			)
			(layer "F.Fab")
		)
		(fp_line
			(start -0.12065 -0.305054)
			(end -0.12065 -0.2794)
			(stroke
				(width 0.1)
				(type default)
			)
			(layer "F.Fab")
		)
		(fp_line
			(start -0.67945 0.3048)
			(end -0.67945 -0.305054)
			(stroke
				(width 0.1)
				(type default)
			)
			(layer "F.Fab")
		)
		(fp_line
			(start -0.67945 -0.305054)
			(end -0.12065 -0.305054)
			(stroke
				(width 0.1)
				(type default)
			)
			(layer "F.Fab")
		)
		(pad "1" smd circle
			(at -0.40005 0 180)
			(size 0 0)
			(layers "F.Cu" "F.Mask" "F.Paste")
			(net "VSENSE_PVDDCR_CPU1_P0_DP")
		)
		(pad "2" smd circle
			(at 0.40005 0 180)
			(size 0 0)
			(layers "F.Cu" "F.Mask" "F.Paste")
			(net "PVDDCR_CPU1_P0")
		)
	)
)
